# T6G (Grand Teton) — schematic netlist excerpt (pin names and nets, part order shuffled) for the footprints in the layout excerpt that follows; sources: Cadence DE-HDL packaged netlist, KiCad conversion of 04192023_DAF0TMB3IC0_F0TG_MB_C_brd_V02_OCP.brd

C1077  Q_CAP  10UF 16V 10% X6S  pkg C0805  page 258 : A = P3V3_MAX11617_2_VDD ; B = GND
C425  Q_CAP  1UF 4V 20% X6S  pkg 0201  page 345 : A = P0V9_CPU1_RT2_2A ; B = GND
R15  Q_RES  0 5% CHIP  pkg 0402LF  page 85 : A = JTAG_PLD_TCK ; B = JTAG_SCM_PLD_TCK

(kicad_pcb
	(version 20260206)
	(generator "pcbnew")
	(generator_version "10.0")
	(general
		(thickness 1.6)
		(legacy_teardrops no)
	)
	(paper "A4")
	(title_block
		(title "04192023_DAF0TMB3IC0_F0TG_MB_C_brd_V02_OCP.brd")
		(comment 1 "Grand Teton / footprints 5427-5429 of 8354")
	)
	(layers
		(0 "F.Cu" signal "TOP")
		(4 "In1.Cu" signal "GND")
		(6 "In2.Cu" signal "IN1")
		(8 "In3.Cu" signal "GND1")
		(10 "In4.Cu" signal "IN2")
		(12 "In5.Cu" signal "GND2")
		(14 "In6.Cu" signal "IN3")
		(16 "In7.Cu" signal "GND3")
		(18 "In8.Cu" signal "VCC")
		(20 "In9.Cu" signal "VCC1")
		(22 "In10.Cu" signal "GND4")
		(24 "In11.Cu" signal "IN4")
		(26 "In12.Cu" signal "GND5")
		(28 "In13.Cu" signal "IN5")
		(30 "In14.Cu" signal "GND6")
		(32 "In15.Cu" signal "IN6")
		(34 "In16.Cu" signal "GND7")
		(2 "B.Cu" signal "BOTTOM")
		(9 "F.Adhes" user "F.Adhesive")
		(11 "B.Adhes" user "B.Adhesive")
		(13 "F.Paste" user "Package Geometry/Pastemask Top")
		(15 "B.Paste" user "Package Geometry/Pastemask Bottom")
		(5 "F.SilkS" user "Ref Des/Silkscreen Top")
		(7 "B.SilkS" user "Ref Des/Silkscreen Bottom")
		(1 "F.Mask" user "Board Geometry/Soldermask Top")
		(3 "B.Mask" user "Board Geometry/Soldermask Bottom")
		(17 "Dwgs.User" user "User.Drawings")
		(19 "Cmts.User" user "User.Comments")
		(21 "Eco1.User" user "User.Eco1")
		(23 "Eco2.User" user "User.Eco2")
		(25 "Edge.Cuts" user "Board Geometry/Outline")
		(27 "Margin" user)
		(31 "F.CrtYd" user "Package Geometry/Place Bound Top")
		(29 "B.CrtYd" user "Package Geometry/Place Bound Bottom")
		(35 "F.Fab" user "Ref Des/Assembly Top")
		(33 "B.Fab" user "Ref Des/Assembly Bottom")
	)
	(footprint ""
		(layer "B.Cu")
		(at 136.897872 -64.04229 90)
		(property "Reference" "R15"
			(at 0 0 90)
			(layer "B.SilkS")
			(hide yes)
			(effects
				(font
					(size 1.27 1.27)
				)
				(justify mirror)
			)
		)
		(property "Value" ""
			(at 0 0 90)
			(layer "B.Fab")
			(effects
				(font
					(size 1.27 1.27)
				)
				(justify mirror)
			)
		)
		(duplicate_pad_numbers_are_jumpers no)
		(fp_line
			(start 0.7874 -0.4064)
			(end -0.7874 -0.4064)
			(stroke
				(width 0.1524)
				(type default)
			)
			(layer "B.SilkS")
		)
		(fp_line
			(start -0.7874 -0.4064)
			(end -0.7874 0.4064)
			(stroke
				(width 0.1524)
				(type default)
			)
			(layer "B.SilkS")
		)
		(fp_line
			(start 0.7874 0.4064)
			(end 0.7874 -0.4064)
			(stroke
				(width 0.1524)
				(type default)
			)
			(layer "B.SilkS")
		)
		(fp_line
			(start -0.7874 0.4064)
			(end 0.7874 0.4064)
			(stroke
				(width 0.1524)
				(type default)
			)
			(layer "B.SilkS")
		)
		(fp_line
			(start 0.67945 -0.305054)
			(end 0.12065 -0.305054)
			(stroke
				(width 0.1)
				(type default)
			)
			(layer "B.Fab")
		)
		(fp_line
			(start 0.12065 -0.305054)
			(end 0.12065 -0.2794)
			(stroke
				(width 0.1)
				(type default)
			)
			(layer "B.Fab")
		)
		(fp_line
			(start -0.12065 -0.3048)
			(end -0.67945 -0.3048)
			(stroke
				(width 0.1)
				(type default)
			)
			(layer "B.Fab")
		)
		(fp_line
			(start -0.67945 -0.3048)
			(end -0.67945 0.3048)
			(stroke
				(width 0.1)
				(type default)
			)
			(layer "B.Fab")
		)
		(fp_line
			(start 0.12065 -0.2794)
			(end -0.12065 -0.2794)
			(stroke
				(width 0.1)
				(type default)
			)
			(layer "B.Fab")
		)
		(fp_line
			(start -0.12065 -0.2794)
			(end -0.12065 -0.3048)
			(stroke
				(width 0.1)
				(type default)
			)
			(layer "B.Fab")
		)
		(fp_line
			(start 0.12065 0.2794)
			(end 0.12065 0.3048)
			(stroke
				(width 0.1)
				(type default)
			)
			(layer "B.Fab")
		)
		(fp_line
			(start -0.120396 0.2794)
			(end 0.12065 0.2794)
			(stroke
				(width 0.1)
				(type default)
			)
			(layer "B.Fab")
		)
		(fp_line
			(start 0.67945 0.3048)
			(end 0.67945 -0.305054)
			(stroke
				(width 0.1)
				(type default)
			)
			(layer "B.Fab")
		)
		(fp_line
			(start 0.12065 0.3048)
			(end 0.67945 0.3048)
			(stroke
				(width 0.1)
				(type default)
			)
			(layer "B.Fab")
		)
		(fp_line
			(start -0.120396 0.3048)
			(end -0.120396 0.2794)
			(stroke
				(width 0.1)
				(type default)
			)
			(layer "B.Fab")
		)
		(fp_line
			(start -0.67945 0.3048)
			(end -0.120396 0.3048)
			(stroke
				(width 0.1)
				(type default)
			)
			(layer "B.Fab")
		)
		(pad "1" smd circle
			(at 0.40005 0 270)
			(size 0 0)
			(layers "B.Cu" "B.Mask" "B.Paste")
			(net "JTAG_PLD_TCK")
		)
		(pad "2" smd circle
			(at -0.40005 0 270)
			(size 0 0)
			(layers "B.Cu" "B.Mask" "B.Paste")
			(net "JTAG_SCM_PLD_TCK")
		)
	)
	(footprint ""
		(layer "B.Cu")
		(at 244.348 -329.057 -90)
		(property "Reference" "C1077"
			(at 0 0 90)
			(layer "B.SilkS")
			(hide yes)
			(effects
				(font
					(size 1.27 1.27)
				)
				(justify mirror)
			)
		)
		(property "Value" ""
			(at 0 0 90)
			(layer "B.Fab")
			(effects
				(font
					(size 1.27 1.27)
				)
				(justify mirror)
			)
		)
		(duplicate_pad_numbers_are_jumpers no)
		(fp_line
			(start -1.524 0.762)
			(end 1.524 0.762)
			(stroke
				(width 0.1524)
				(type default)
			)
			(layer "B.SilkS")
		)
		(fp_line
			(start 1.524 0.762)
			(end 1.524 -0.762)
			(stroke
				(width 0.1524)
				(type default)
			)
			(layer "B.SilkS")
		)
		(fp_line
			(start -1.524 -0.762)
			(end -1.524 0.762)
			(stroke
				(width 0.1524)
				(type default)
			)
			(layer "B.SilkS")
		)
		(fp_line
			(start 1.524 -0.762)
			(end -1.524 -0.762)
			(stroke
				(width 0.1524)
				(type default)
			)
			(layer "B.SilkS")
		)
		(fp_line
			(start -1.1049 0.724916)
			(end -1.1049 -0.724916)
			(stroke
				(width 0.1)
				(type default)
			)
			(layer "B.Fab")
		)
		(fp_line
			(start 1.1049 0.724916)
			(end -1.1049 0.724916)
			(stroke
				(width 0.1)
				(type default)
			)
			(layer "B.Fab")
		)
		(fp_line
			(start -1.1049 -0.724916)
			(end 1.1049 -0.724916)
			(stroke
				(width 0.1)
				(type default)
			)
			(layer "B.Fab")
		)
		(fp_line
			(start 1.1049 -0.724916)
			(end 1.1049 0.724916)
			(stroke
				(width 0.1)
				(type default)
			)
			(layer "B.Fab")
		)
		(pad "1" smd rect
			(at 0.889 0 270)
			(size 1.016 1.27)
			(layers "B.Cu" "B.Mask" "B.Paste")
			(net "P3V3_MAX11617_2_VDD")
		)
		(pad "2" smd rect
			(at -0.889 0 270)
			(size 1.016 1.27)
			(layers "B.Cu" "B.Mask" "B.Paste")
			(net "GND")
		)
	)
	(footprint ""
		(layer "B.Cu")
		(at 148.206206 -386.766562 90)
		(property "Reference" "C425"
			(at 0 0 90)
			(layer "B.SilkS")
			(hide yes)
			(effects
				(font
					(size 1.27 1.27)
				)
				(justify mirror)
			)
		)
		(property "Value" ""
			(at 0 0 90)
			(layer "B.Fab")
			(effects
				(font
					(size 1.27 1.27)
				)
				(justify mirror)
			)
		)
		(duplicate_pad_numbers_are_jumpers no)
		(fp_line
			(start 0.299974 -0.150114)
			(end -0.299974 -0.150114)
			(stroke
				(width 0.1)
				(type default)
			)
			(layer "B.Fab")
		)
		(fp_line
			(start -0.299974 -0.150114)
			(end -0.299974 0.150114)
			(stroke
				(width 0.1)
				(type default)
			)
			(layer "B.Fab")
		)
		(fp_line
			(start 0.299974 0.150114)
			(end 0.299974 -0.150114)
			(stroke
				(width 0.1)
				(type default)
			)
			(layer "B.Fab")
		)
		(fp_line
			(start -0.299974 0.150114)
			(end 0.299974 0.150114)
			(stroke
				(width 0.1)
				(type default)
			)
			(layer "B.Fab")
		)
		(pad "1" smd rect
			(at 0.2667 0 270)
			(size 0.3048 0.381)
			(layers "B.Cu" "B.Mask" "B.Paste")
			(net "P0V9_CPU1_RT2_2A")
		)
		(pad "2" smd rect
			(at -0.2667 0 270)
			(size 0.3048 0.381)
			(layers "B.Cu" "B.Mask" "B.Paste")
			(net "GND")
		)
	)
)
